(kicad_pcb
	(version 20260206)
	(generator "pcbnew")
	(generator_version "10.0")
	(general
		(thickness 1.6)
		(legacy_teardrops no)
	)
	(paper "A4")
	(title_block
		(title "04192023_DAF0TMB3IC0_F0TG_MB_C_brd_V02_OCP.brd")
		(comment 1 "Grand Teton / footprints 7145-7150 of 8354")
	)
	(layers
		(0 "F.Cu" signal "TOP")
		(4 "In1.Cu" signal "GND")
		(6 "In2.Cu" signal "IN1")
		(8 "In3.Cu" signal "GND1")
		(10 "In4.Cu" signal "IN2")
		(12 "In5.Cu" signal "GND2")
		(14 "In6.Cu" signal "IN3")
		(16 "In7.Cu" signal "GND3")
		(18 "In8.Cu" signal "VCC")
		(20 "In9.Cu" signal "VCC1")
		(22 "In10.Cu" signal "GND4")
		(24 "In11.Cu" signal "IN4")
		(26 "In12.Cu" signal "GND5")
		(28 "In13.Cu" signal "IN5")
		(30 "In14.Cu" signal "GND6")
		(32 "In15.Cu" signal "IN6")
		(34 "In16.Cu" signal "GND7")
		(2 "B.Cu" signal "BOTTOM")
		(9 "F.Adhes" user "F.Adhesive")
		(11 "B.Adhes" user "B.Adhesive")
		(13 "F.Paste" user "Package Geometry/Pastemask Top")
		(15 "B.Paste" user "Package Geometry/Pastemask Bottom")
		(5 "F.SilkS" user "Ref Des/Silkscreen Top")
		(7 "B.SilkS" user "Ref Des/Silkscreen Bottom")
		(1 "F.Mask" user "Board Geometry/Soldermask Top")
		(3 "B.Mask" user "Board Geometry/Soldermask Bottom")
		(17 "Dwgs.User" user "User.Drawings")
		(19 "Cmts.User" user "User.Comments")
		(21 "Eco1.User" user "User.Eco1")
		(23 "Eco2.User" user "User.Eco2")
		(25 "Edge.Cuts" user "Board Geometry/Outline")
		(27 "Margin" user)
		(31 "F.CrtYd" user "Package Geometry/Place Bound Top")
		(29 "B.CrtYd" user "Package Geometry/Place Bound Bottom")
		(35 "F.Fab" user "Ref Des/Assembly Top")
		(33 "B.Fab" user "Ref Des/Assembly Bottom")
	)
	(footprint ""
		(layer "B.Cu")
		(at 101.004878 -147.04441 -90)
		(property "Reference" "PC245"
			(at 0 0 90)
			(layer "B.SilkS")
			(hide yes)
			(effects
				(font
					(size 1.27 1.27)
				)
				(justify mirror)
			)
		)
		(property "Value" ""
			(at 0 0 90)
			(layer "B.Fab")
			(effects
				(font
					(size 1.27 1.27)
				)
				(justify mirror)
			)
		)
		(duplicate_pad_numbers_are_jumpers no)
		(fp_line
			(start -0.7874 0.4064)
			(end 0.7874 0.4064)
			(stroke
				(width 0.1524)
				(type default)
			)
			(layer "B.SilkS")
		)
		(fp_line
			(start 0.7874 0.4064)
			(end 0.7874 -0.4064)
			(stroke
				(width 0.1524)
				(type default)
			)
			(layer "B.SilkS")
		)
		(fp_line
			(start -0.7874 -0.4064)
			(end -0.7874 0.4064)
			(stroke
				(width 0.1524)
				(type default)
			)
			(layer "B.SilkS")
		)
		(fp_line
			(start 0.7874 -0.4064)
			(end -0.7874 -0.4064)
			(stroke
				(width 0.1524)
				(type default)
			)
			(layer "B.SilkS")
		)
		(fp_line
			(start -0.67945 0.3048)
			(end -0.120396 0.3048)
			(stroke
				(width 0.1)
				(type default)
			)
			(layer "B.Fab")
		)
		(fp_line
			(start -0.120396 0.3048)
			(end -0.120396 0.2794)
			(stroke
				(width 0.1)
				(type default)
			)
			(layer "B.Fab")
		)
		(fp_line
			(start 0.12065 0.3048)
			(end 0.67945 0.3048)
			(stroke
				(width 0.1)
				(type default)
			)
			(layer "B.Fab")
		)
		(fp_line
			(start 0.67945 0.3048)
			(end 0.67945 -0.305054)
			(stroke
				(width 0.1)
				(type default)
			)
			(layer "B.Fab")
		)
		(fp_line
			(start -0.120396 0.2794)
			(end 0.12065 0.2794)
			(stroke
				(width 0.1)
				(type default)
			)
			(layer "B.Fab")
		)
		(fp_line
			(start 0.12065 0.2794)
			(end 0.12065 0.3048)
			(stroke
				(width 0.1)
				(type default)
			)
			(layer "B.Fab")
		)
		(fp_line
			(start -0.12065 -0.2794)
			(end -0.12065 -0.3048)
			(stroke
				(width 0.1)
				(type default)
			)
			(layer "B.Fab")
		)
		(fp_line
			(start 0.12065 -0.2794)
			(end -0.12065 -0.2794)
			(stroke
				(width 0.1)
				(type default)
			)
			(layer "B.Fab")
		)
		(fp_line
			(start -0.67945 -0.3048)
			(end -0.67945 0.3048)
			(stroke
				(width 0.1)
				(type default)
			)
			(layer "B.Fab")
		)
		(fp_line
			(start -0.12065 -0.3048)
			(end -0.67945 -0.3048)
			(stroke
				(width 0.1)
				(type default)
			)
			(layer "B.Fab")
		)
		(fp_line
			(start 0.12065 -0.305054)
			(end 0.12065 -0.2794)
			(stroke
				(width 0.1)
				(type default)
			)
			(layer "B.Fab")
		)
		(fp_line
			(start 0.67945 -0.305054)
			(end 0.12065 -0.305054)
			(stroke
				(width 0.1)
				(type default)
			)
			(layer "B.Fab")
		)
		(pad "1" smd circle
			(at 0.40005 0 90)
			(size 0 0)
			(layers "B.Cu" "B.Mask" "B.Paste")
			(net "VSENSE_PVDDCR_SOC_P1_VSEN1")
		)
		(pad "2" smd circle
			(at -0.40005 0 90)
			(size 0 0)
			(layers "B.Cu" "B.Mask" "B.Paste")
			(net "VSENSE_VSS_SENSE_A_P1")
		)
	)
	(footprint ""
		(layer "B.Cu")
		(at 167.772588 -194.8942 180)
		(property "Reference" "R1586"
			(at 0 0 0)
			(layer "B.SilkS")
			(hide yes)
			(effects
				(font
					(size 1.27 1.27)
				)
				(justify mirror)
			)
		)
		(property "Value" ""
			(at 0 0 0)
			(layer "B.Fab")
			(effects
				(font
					(size 1.27 1.27)
				)
				(justify mirror)
			)
		)
		(duplicate_pad_numbers_are_jumpers no)
		(fp_line
			(start 0.7874 0.4064)
			(end 0.7874 -0.4064)
			(stroke
				(width 0.1524)
				(type default)
			)
			(layer "B.SilkS")
		)
		(fp_line
			(start 0.7874 -0.4064)
			(end -0.7874 -0.4064)
			(stroke
				(width 0.1524)
				(type default)
			)
			(layer "B.SilkS")
		)
		(fp_line
			(start -0.7874 0.4064)
			(end 0.7874 0.4064)
			(stroke
				(width 0.1524)
				(type default)
			)
			(layer "B.SilkS")
		)
		(fp_line
			(start -0.7874 -0.4064)
			(end -0.7874 0.4064)
			(stroke
				(width 0.1524)
				(type default)
			)
			(layer "B.SilkS")
		)
		(fp_line
			(start 0.67945 0.3048)
			(end 0.67945 -0.305054)
			(stroke
				(width 0.1)
				(type default)
			)
			(layer "B.Fab")
		)
		(fp_line
			(start 0.67945 -0.305054)
			(end 0.12065 -0.305054)
			(stroke
				(width 0.1)
				(type default)
			)
			(layer "B.Fab")
		)
		(fp_line
			(start 0.12065 0.3048)
			(end 0.67945 0.3048)
			(stroke
				(width 0.1)
				(type default)
			)
			(layer "B.Fab")
		)
		(fp_line
			(start 0.12065 0.2794)
			(end 0.12065 0.3048)
			(stroke
				(width 0.1)
				(type default)
			)
			(layer "B.Fab")
		)
		(fp_line
			(start 0.12065 -0.2794)
			(end -0.12065 -0.2794)
			(stroke
				(width 0.1)
				(type default)
			)
			(layer "B.Fab")
		)
		(fp_line
			(start 0.12065 -0.305054)
			(end 0.12065 -0.2794)
			(stroke
				(width 0.1)
				(type default)
			)
			(layer "B.Fab")
		)
		(fp_line
			(start -0.120396 0.3048)
			(end -0.120396 0.2794)
			(stroke
				(width 0.1)
				(type default)
			)
			(layer "B.Fab")
		)
		(fp_line
			(start -0.120396 0.2794)
			(end 0.12065 0.2794)
			(stroke
				(width 0.1)
				(type default)
			)
			(layer "B.Fab")
		)
		(fp_line
			(start -0.12065 -0.2794)
			(end -0.12065 -0.3048)
			(stroke
				(width 0.1)
				(type default)
			)
			(layer "B.Fab")
		)
		(fp_line
			(start -0.12065 -0.3048)
			(end -0.67945 -0.3048)
			(stroke
				(width 0.1)
				(type default)
			)
			(layer "B.Fab")
		)
		(fp_line
			(start -0.67945 0.3048)
			(end -0.120396 0.3048)
			(stroke
				(width 0.1)
				(type default)
			)
			(layer "B.Fab")
		)
		(fp_line
			(start -0.67945 -0.3048)
			(end -0.67945 0.3048)
			(stroke
				(width 0.1)
				(type default)
			)
			(layer "B.Fab")
		)
		(pad "1" smd circle
			(at 0.40005 0)
			(size 0 0)
			(layers "B.Cu" "B.Mask" "B.Paste")
			(net "I3C_SPD_DDRGL_CPU1_SCL")
		)
		(pad "2" smd circle
			(at -0.40005 0)
			(size 0 0)
			(layers "B.Cu" "B.Mask" "B.Paste")
			(net "I3C_SPD_DDRG_CPU1_SCL")
		)
	)
	(footprint ""
		(layer "B.Cu")
		(at 125.389386 -252.543564)
		(property "Reference" "C2471"
			(at 0 0 0)
			(layer "B.SilkS")
			(hide yes)
			(effects
				(font
					(size 1.27 1.27)
				)
				(justify mirror)
			)
		)
		(property "Value" ""
			(at 0 0 0)
			(layer "B.Fab")
			(effects
				(font
					(size 1.27 1.27)
				)
				(justify mirror)
			)
		)
		(duplicate_pad_numbers_are_jumpers no)
		(fp_line
			(start -0.7874 -0.4064)
			(end -0.7874 0.4064)
			(stroke
				(width 0.1524)
				(type default)
			)
			(layer "B.SilkS")
		)
		(fp_line
			(start -0.7874 0.4064)
			(end 0.7874 0.4064)
			(stroke
				(width 0.1524)
				(type default)
			)
			(layer "B.SilkS")
		)
		(fp_line
			(start 0.7874 -0.4064)
			(end -0.7874 -0.4064)
			(stroke
				(width 0.1524)
				(type default)
			)
			(layer "B.SilkS")
		)
		(fp_line
			(start 0.7874 0.4064)
			(end 0.7874 -0.4064)
			(stroke
				(width 0.1524)
				(type default)
			)
			(layer "B.SilkS")
		)
		(fp_line
			(start -0.67945 -0.3048)
			(end -0.67945 0.3048)
			(stroke
				(width 0.1)
				(type default)
			)
			(layer "B.Fab")
		)
		(fp_line
			(start -0.67945 0.3048)
			(end -0.120396 0.3048)
			(stroke
				(width 0.1)
				(type default)
			)
			(layer "B.Fab")
		)
		(fp_line
			(start -0.12065 -0.3048)
			(end -0.67945 -0.3048)
			(stroke
				(width 0.1)
				(type default)
			)
			(layer "B.Fab")
		)
		(fp_line
			(start -0.12065 -0.2794)
			(end -0.12065 -0.3048)
			(stroke
				(width 0.1)
				(type default)
			)
			(layer "B.Fab")
		)
		(fp_line
			(start -0.120396 0.2794)
			(end 0.12065 0.2794)
			(stroke
				(width 0.1)
				(type default)
			)
			(layer "B.Fab")
		)
		(fp_line
			(start -0.120396 0.3048)
			(end -0.120396 0.2794)
			(stroke
				(width 0.1)
				(type default)
			)
			(layer "B.Fab")
		)
		(fp_line
			(start 0.12065 -0.305054)
			(end 0.12065 -0.2794)
			(stroke
				(width 0.1)
				(type default)
			)
			(layer "B.Fab")
		)
		(fp_line
			(start 0.12065 -0.2794)
			(end -0.12065 -0.2794)
			(stroke
				(width 0.1)
				(type default)
			)
			(layer "B.Fab")
		)
		(fp_line
			(start 0.12065 0.2794)
			(end 0.12065 0.3048)
			(stroke
				(width 0.1)
				(type default)
			)
			(layer "B.Fab")
		)
		(fp_line
			(start 0.12065 0.3048)
			(end 0.67945 0.3048)
			(stroke
				(width 0.1)
				(type default)
			)
			(layer "B.Fab")
		)
		(fp_line
			(start 0.67945 -0.305054)
			(end 0.12065 -0.305054)
			(stroke
				(width 0.1)
				(type default)
			)
			(layer "B.Fab")
		)
		(fp_line
			(start 0.67945 0.3048)
			(end 0.67945 -0.305054)
			(stroke
				(width 0.1)
				(type default)
			)
			(layer "B.Fab")
		)
		(pad "1" smd circle
			(at 0.40005 0 180)
			(size 0 0)
			(layers "B.Cu" "B.Mask" "B.Paste")
			(net "PVDDCR_SOC_P1")
		)
		(pad "2" smd circle
			(at -0.40005 0 180)
			(size 0 0)
			(layers "B.Cu" "B.Mask" "B.Paste")
			(net "GND")
		)
	)
	(footprint ""
		(layer "B.Cu")
		(at 421.95877 -422.28897)
		(property "Reference" "R681"
			(at 0 0 0)
			(layer "B.SilkS")
			(hide yes)
			(effects
				(font
					(size 1.27 1.27)
				)
				(justify mirror)
			)
		)
		(property "Value" ""
			(at 0 0 0)
			(layer "B.Fab")
			(effects
				(font
					(size 1.27 1.27)
				)
				(justify mirror)
			)
		)
		(duplicate_pad_numbers_are_jumpers no)
		(fp_line
			(start -0.32512 -0.175006)
			(end -0.32512 0.175006)
			(stroke
				(width 0.1)
				(type default)
			)
			(layer "B.Fab")
		)
		(fp_line
			(start -0.32512 0.175006)
			(end 0.32512 0.175006)
			(stroke
				(width 0.1)
				(type default)
			)
			(layer "B.Fab")
		)
		(fp_line
			(start 0.32512 -0.175006)
			(end -0.32512 -0.175006)
			(stroke
				(width 0.1)
				(type default)
			)
			(layer "B.Fab")
		)
		(fp_line
			(start 0.32512 0.175006)
			(end 0.32512 -0.175006)
			(stroke
				(width 0.1)
				(type default)
			)
			(layer "B.Fab")
		)
		(pad "1" smd rect
			(at 0.2667 0 180)
			(size 0.3048 0.381)
			(layers "B.Cu" "B.Mask" "B.Paste")
			(net "SMB_RT_CPU0_P2_ROM_MUX_1D_SDA")
		)
		(pad "2" smd rect
			(at -0.2667 0)
			(size 0.3048 0.381)
			(layers "B.Cu" "B.Mask" "B.Paste")
			(net "SMB_RT_CPU0_P2_ROM_MUX_1D_R_SDA")
		)
	)
	(footprint ""
		(layer "B.Cu")
		(at 231.874822 -323.913754 180)
		(property "Reference" "R1245"
			(at 0 0 0)
			(layer "B.SilkS")
			(hide yes)
			(effects
				(font
					(size 1.27 1.27)
				)
				(justify mirror)
			)
		)
		(property "Value" ""
			(at 0 0 0)
			(layer "B.Fab")
			(effects
				(font
					(size 1.27 1.27)
				)
				(justify mirror)
			)
		)
		(duplicate_pad_numbers_are_jumpers no)
		(fp_line
			(start 0.7874 0.4064)
			(end 0.7874 -0.4064)
			(stroke
				(width 0.1524)
				(type default)
			)
			(layer "B.SilkS")
		)
		(fp_line
			(start 0.7874 -0.4064)
			(end -0.7874 -0.4064)
			(stroke
				(width 0.1524)
				(type default)
			)
			(layer "B.SilkS")
		)
		(fp_line
			(start -0.7874 0.4064)
			(end 0.7874 0.4064)
			(stroke
				(width 0.1524)
				(type default)
			)
			(layer "B.SilkS")
		)
		(fp_line
			(start -0.7874 -0.4064)
			(end -0.7874 0.4064)
			(stroke
				(width 0.1524)
				(type default)
			)
			(layer "B.SilkS")
		)
		(fp_line
			(start 0.67945 0.3048)
			(end 0.67945 -0.305054)
			(stroke
				(width 0.1)
				(type default)
			)
			(layer "B.Fab")
		)
		(fp_line
			(start 0.67945 -0.305054)
			(end 0.12065 -0.305054)
			(stroke
				(width 0.1)
				(type default)
			)
			(layer "B.Fab")
		)
		(fp_line
			(start 0.12065 0.3048)
			(end 0.67945 0.3048)
			(stroke
				(width 0.1)
				(type default)
			)
			(layer "B.Fab")
		)
		(fp_line
			(start 0.12065 0.2794)
			(end 0.12065 0.3048)
			(stroke
				(width 0.1)
				(type default)
			)
			(layer "B.Fab")
		)
		(fp_line
			(start 0.12065 -0.2794)
			(end -0.12065 -0.2794)
			(stroke
				(width 0.1)
				(type default)
			)
			(layer "B.Fab")
		)
		(fp_line
			(start 0.12065 -0.305054)
			(end 0.12065 -0.2794)
			(stroke
				(width 0.1)
				(type default)
			)
			(layer "B.Fab")
		)
		(fp_line
			(start -0.120396 0.3048)
			(end -0.120396 0.2794)
			(stroke
				(width 0.1)
				(type default)
			)
			(layer "B.Fab")
		)
		(fp_line
			(start -0.120396 0.2794)
			(end 0.12065 0.2794)
			(stroke
				(width 0.1)
				(type default)
			)
			(layer "B.Fab")
		)
		(fp_line
			(start -0.12065 -0.2794)
			(end -0.12065 -0.3048)
			(stroke
				(width 0.1)
				(type default)
			)
			(layer "B.Fab")
		)
		(fp_line
			(start -0.12065 -0.3048)
			(end -0.67945 -0.3048)
			(stroke
				(width 0.1)
				(type default)
			)
			(layer "B.Fab")
		)
		(fp_line
			(start -0.67945 0.3048)
			(end -0.120396 0.3048)
			(stroke
				(width 0.1)
				(type default)
			)
			(layer "B.Fab")
		)
		(fp_line
			(start -0.67945 -0.3048)
			(end -0.67945 0.3048)
			(stroke
				(width 0.1)
				(type default)
			)
			(layer "B.Fab")
		)
		(pad "1" smd rect
			(at 0.40005 0 180)
			(size 0.4572 0.508)
			(layers "B.Cu" "B.Mask" "B.Paste")
			(net "P1V2_AUX_ADC")
		)
		(pad "2" smd rect
			(at -0.40005 0 180)
			(size 0.4572 0.508)
			(layers "B.Cu" "B.Mask" "B.Paste")
			(net "P1V2_AUX_ADC_MAM")
		)
	)
	(footprint ""
		(layer "B.Cu")
		(at 164.325554 -350.762062)
		(property "Reference" "PR604"
			(at 0 0 0)
			(layer "B.SilkS")
			(hide yes)
			(effects
				(font
					(size 1.27 1.27)
				)
				(justify mirror)
			)
		)
		(property "Value" ""
			(at 0 0 0)
			(layer "B.Fab")
			(effects
				(font
					(size 1.27 1.27)
				)
				(justify mirror)
			)
		)
		(duplicate_pad_numbers_are_jumpers no)
		(fp_line
			(start -0.7874 -0.4064)
			(end -0.7874 0.4064)
			(stroke
				(width 0.1524)
				(type default)
			)
			(layer "B.SilkS")
		)
		(fp_line
			(start -0.7874 0.4064)
			(end 0.7874 0.4064)
			(stroke
				(width 0.1524)
				(type default)
			)
			(layer "B.SilkS")
		)
		(fp_line
			(start 0.7874 -0.4064)
			(end -0.7874 -0.4064)
			(stroke
				(width 0.1524)
				(type default)
			)
			(layer "B.SilkS")
		)
		(fp_line
			(start 0.7874 0.4064)
			(end 0.7874 -0.4064)
			(stroke
				(width 0.1524)
				(type default)
			)
			(layer "B.SilkS")
		)
		(fp_line
			(start -0.67945 -0.3048)
			(end -0.67945 0.3048)
			(stroke
				(width 0.1)
				(type default)
			)
			(layer "B.Fab")
		)
		(fp_line
			(start -0.67945 0.3048)
			(end -0.120396 0.3048)
			(stroke
				(width 0.1)
				(type default)
			)
			(layer "B.Fab")
		)
		(fp_line
			(start -0.12065 -0.3048)
			(end -0.67945 -0.3048)
			(stroke
				(width 0.1)
				(type default)
			)
			(layer "B.Fab")
		)
		(fp_line
			(start -0.12065 -0.2794)
			(end -0.12065 -0.3048)
			(stroke
				(width 0.1)
				(type default)
			)
			(layer "B.Fab")
		)
		(fp_line
			(start -0.120396 0.2794)
			(end 0.12065 0.2794)
			(stroke
				(width 0.1)
				(type default)
			)
			(layer "B.Fab")
		)
		(fp_line
			(start -0.120396 0.3048)
			(end -0.120396 0.2794)
			(stroke
				(width 0.1)
				(type default)
			)
			(layer "B.Fab")
		)
		(fp_line
			(start 0.12065 -0.305054)
			(end 0.12065 -0.2794)
			(stroke
				(width 0.1)
				(type default)
			)
			(layer "B.Fab")
		)
		(fp_line
			(start 0.12065 -0.2794)
			(end -0.12065 -0.2794)
			(stroke
				(width 0.1)
				(type default)
			)
			(layer "B.Fab")
		)
		(fp_line
			(start 0.12065 0.2794)
			(end 0.12065 0.3048)
			(stroke
				(width 0.1)
				(type default)
			)
			(layer "B.Fab")
		)
		(fp_line
			(start 0.12065 0.3048)
			(end 0.67945 0.3048)
			(stroke
				(width 0.1)
				(type default)
			)
			(layer "B.Fab")
		)
		(fp_line
			(start 0.67945 -0.305054)
			(end 0.12065 -0.305054)
			(stroke
				(width 0.1)
				(type default)
			)
			(layer "B.Fab")
		)
		(fp_line
			(start 0.67945 0.3048)
			(end 0.67945 -0.305054)
			(stroke
				(width 0.1)
				(type default)
			)
			(layer "B.Fab")
		)
		(pad "1" smd circle
			(at 0.40005 0 180)
			(size 0 0)
			(layers "B.Cu" "B.Mask" "B.Paste")
			(net "PVDD11_S3_P1_VINSEN")
		)
		(pad "2" smd circle
			(at -0.40005 0 180)
			(size 0 0)
			(layers "B.Cu" "B.Mask" "B.Paste")
			(net "GND")
		)
	)
)
